# BASEBOARD_FAB2 (Tioga Pass) — schematic netlist excerpt (pin names and nets, part order shuffled) for the footprints in the layout excerpt that follows; sources: Cadence DE-HDL packaged netlist, KiCad conversion of Wiwynn_Tioga_Pass_MB.brd

R3P15  RES  150.0 1% CHIP  pkg 0402  page 211 : A = SVID_CLK0_CPU0_R ; B = SVID_CLK_PVCCIO_CPU0

T1D18  TEST-PAD-12P-1-GP-U  pkg DISCRET-GB1  page 258
  DP  = L5_85OHM_10INCH_DN
  DN  = L5_85OHM_10INCH_DP
  GND(0)  = GND
  GND(1)  = GND
  GND(2)  = GND
  GND(3)  = GND
  GND(4)  = GND
  GND(5)  = GND
  GND(6)  = GND
  GND(7)  = GND
  GND(8)  = GND
  GND(9)  = GND

(kicad_pcb
	(version 20260206)
	(generator "pcbnew")
	(generator_version "10.0")
	(general
		(thickness 1.6)
		(legacy_teardrops no)
	)
	(paper "A4")
	(title_block
		(title "Wiwynn_Tioga_Pass_MB.brd")
		(comment 1 "Tioga Pass / footprints 2656-2657 of 4770")
	)
	(layers
		(0 "F.Cu" signal "TOP")
		(4 "In1.Cu" signal "L2GND")
		(6 "In2.Cu" signal "L3")
		(8 "In3.Cu" signal "L4GND")
		(10 "In4.Cu" signal "L5")
		(12 "In5.Cu" signal "L6GND")
		(14 "In6.Cu" signal "L7VCC")
		(16 "In7.Cu" signal "L8VCC")
		(18 "In8.Cu" signal "L9GND")
		(20 "In9.Cu" signal "L10")
		(22 "In10.Cu" signal "L11GND")
		(24 "In11.Cu" signal "L12")
		(26 "In12.Cu" signal "L13GND")
		(2 "B.Cu" signal "BOTTOM")
		(9 "F.Adhes" user "F.Adhesive")
		(11 "B.Adhes" user "B.Adhesive")
		(13 "F.Paste" user "Package Geometry/Pastemask Top")
		(15 "B.Paste" user "Package Geometry/Pastemask Bottom")
		(5 "F.SilkS" user "Ref Des/Silkscreen Top")
		(7 "B.SilkS" user "Ref Des/Silkscreen Bottom")
		(1 "F.Mask" user "Board Geometry/Soldermask Top")
		(3 "B.Mask" user "Board Geometry/Soldermask Bottom")
		(17 "Dwgs.User" user "User.Drawings")
		(19 "Cmts.User" user "User.Comments")
		(21 "Eco1.User" user "User.Eco1")
		(23 "Eco2.User" user "User.Eco2")
		(25 "Edge.Cuts" user "Board Geometry/Outline")
		(27 "Margin" user)
		(31 "F.CrtYd" user "Package Geometry/Place Bound Top")
		(29 "B.CrtYd" user "Package Geometry/Place Bound Bottom")
		(35 "F.Fab" user "Ref Des/Assembly Top")
		(33 "B.Fab" user "Ref Des/Assembly Bottom")
	)
	(footprint ""
		(layer "B.Cu")
		(at 341.1982 -86.5632 90)
		(property "Reference" "R3P15"
			(at 0 0 90)
			(layer "B.SilkS")
			(hide yes)
			(effects
				(font
					(size 1.27 1.27)
				)
				(justify mirror)
			)
		)
		(property "Value" ""
			(at 0 0 90)
			(layer "B.Fab")
			(effects
				(font
					(size 1.27 1.27)
				)
				(justify mirror)
			)
		)
		(duplicate_pad_numbers_are_jumpers no)
		(fp_poly
			(pts
				(xy 0.2794 -0.1016) (xy -0.2794 -0.1016) (xy -0.2794 0.9906) (xy 0.2794 0.9906)
			)
			(stroke
				(width 0)
				(type default)
			)
			(fill no)
			(layer "B.CrtYd")
		)
		(fp_line
			(start 0.2794 -0.1016)
			(end 0.2794 0.9906)
			(stroke
				(width 0.1)
				(type default)
			)
			(layer "B.Fab")
		)
		(fp_line
			(start -0.2794 -0.1016)
			(end 0.2794 -0.1016)
			(stroke
				(width 0.1)
				(type default)
			)
			(layer "B.Fab")
		)
		(fp_line
			(start 0.2794 0.9906)
			(end -0.2794 0.9906)
			(stroke
				(width 0.1)
				(type default)
			)
			(layer "B.Fab")
		)
		(fp_line
			(start -0.2794 0.9906)
			(end -0.2794 -0.1016)
			(stroke
				(width 0.1)
				(type default)
			)
			(layer "B.Fab")
		)
		(pad "1" smd rect
			(at 0 0 270)
			(size 0.508 0.508)
			(layers "B.Cu" "B.Mask" "B.Paste")
			(net "SVID_CLK0_CPU0_R")
		)
		(pad "2" smd rect
			(at 0 0.889 270)
			(size 0.508 0.508)
			(layers "B.Cu" "B.Mask" "B.Paste")
			(net "SVID_CLK_PVCCIO_CPU0")
		)
		(zone
			(layer "B.Cu")
			(hatch none 0.5)
			(connect_pads
				(clearance 0)
			)
			(min_thickness 0.25)
			(keepout
				(tracks allowed)
				(vias not_allowed)
				(pads allowed)
				(copperpour not_allowed)
				(footprints allowed)
			)
			(placement
				(enabled no)
				(sheetname "")
			)
			(fill
				(thermal_gap 0.5)
				(thermal_bridge_width 0.5)
				(island_removal_mode 0)
			)
			(polygon
				(pts
					(xy 341.4522 -86.8172) (xy 341.4522 -86.3092) (xy 341.8332 -86.3092) (xy 341.8332 -86.8172)
				)
			)
		)
		(zone
			(layer "B.Cu")
			(hatch none 0.5)
			(connect_pads
				(clearance 0)
			)
			(min_thickness 0.25)
			(keepout
				(tracks not_allowed)
				(vias allowed)
				(pads allowed)
				(copperpour not_allowed)
				(footprints allowed)
			)
			(placement
				(enabled no)
				(sheetname "")
			)
			(fill
				(thermal_gap 0.5)
				(thermal_bridge_width 0.5)
				(island_removal_mode 0)
			)
			(polygon
				(pts
					(xy 341.8332 -86.8172) (xy 341.8332 -86.3092) (xy 341.4522 -86.3092) (xy 341.4522 -86.8172)
				)
			)
		)
	)
	(footprint ""
		(layer "B.Cu")
		(at 388.502906 -164.916612 90)
		(property "Reference" "T1D18"
			(at 0 0 90)
			(layer "B.SilkS")
			(hide yes)
			(effects
				(font
					(size 1.27 1.27)
				)
				(justify mirror)
			)
		)
		(property "Value" "*"
			(at 3.4036 -4.46405 90)
			(unlocked yes)
			(layer "B.Fab")
			(hide yes)
			(effects
				(font
					(size 0.889 0.889)
					(thickness 0.1524)
				)
				(justify mirror)
			)
		)
		(property "Device Type" "TEST-PAD-12P-1-GP-U_DISCRET-GBA"
			(at 3.4036 -5.98805 90)
			(unlocked yes)
			(layer "B.Fab")
			(hide yes)
			(effects
				(font
					(size 0.889 0.889)
					(thickness 0.1524)
				)
				(justify mirror)
			)
		)
		(duplicate_pad_numbers_are_jumpers no)
		(fp_line
			(start 2.3876 -4.826)
			(end -2.3622 -4.826)
			(stroke
				(width 0.1524)
				(type default)
			)
			(layer "B.SilkS")
		)
		(fp_line
			(start -2.3622 -4.826)
			(end -2.3622 3.4798)
			(stroke
				(width 0.1524)
				(type default)
			)
			(layer "B.SilkS")
		)
		(fp_line
			(start 2.3876 3.4798)
			(end 2.3876 -4.826)
			(stroke
				(width 0.1524)
				(type default)
			)
			(layer "B.SilkS")
		)
		(fp_line
			(start -2.3622 3.4798)
			(end 2.3876 3.4798)
			(stroke
				(width 0.1524)
				(type default)
			)
			(layer "B.SilkS")
		)
		(fp_rect
			(start 2.6416 3.7338)
			(end -2.6162 -5.08)
			(stroke
				(width 0)
				(type default)
			)
			(fill no)
			(layer "B.CrtYd")
		)
		(fp_rect
			(start 2.6416 3.7338)
			(end -2.6162 -5.08)
			(stroke
				(width 0)
				(type default)
			)
			(fill no)
			(layer "B.Fab")
		)
		(pad "1" smd circle
			(at -0.496824 -1.301496 270)
			(size 0.6604 0.6604)
			(layers "B.Cu" "B.Mask" "B.Paste")
			(net "L5_85OHM_10INCH_DN")
		)
		(pad "2" smd circle
			(at 0.503936 -1.301496 270)
			(size 0.6604 0.6604)
			(layers "B.Cu" "B.Mask" "B.Paste")
			(net "L5_85OHM_10INCH_DP")
		)
		(pad "3" smd custom
			(at 0.00889 0.370078 270)
			(size 0.74295 0.74295)
			(layers "B.Cu" "B.Mask" "B.Paste")
			(net "GND")
			(options
				(clearance outline)
				(anchor circle)
			)
			(primitives
				(gr_poly
					(pts
						(xy -2.1209 -1.4859) (xy 2.1209 -1.4859) (xy 2.1209 1.4859) (xy 1.08585 1.4859) (xy 1.08585 0.4699)
						(xy -1.08585 0.4699) (xy -1.08585 1.4859) (xy -2.1209 1.4859)
					)
					(width 0)
					(fill yes)
				)
			)
		)
		(pad "4" thru_hole circle
			(at -1.266444 -3.851656 270)
			(size 1.4478 1.4478)
			(drill 1.0414)
			(layers "*.Cu" "*.Mask")
			(remove_unused_layers no)
			(net "GND")
			(clearance 0.1524)
			(thermal_gap 0.1524)
		)
		(pad "5" thru_hole circle
			(at 1.273556 -3.851656 270)
			(size 1.4478 1.4478)
			(drill 1.0414)
			(layers "*.Cu" "*.Mask")
			(remove_unused_layers no)
			(net "GND")
			(clearance 0.1524)
			(thermal_gap 0.1524)
		)
		(pad "6" thru_hole circle
			(at -1.266444 2.498344 270)
			(size 1.4478 1.4478)
			(drill 1.0414)
			(layers "*.Cu" "*.Mask")
			(remove_unused_layers no)
			(net "GND")
			(clearance 0.1524)
			(thermal_gap 0.1524)
		)
		(pad "7" thru_hole circle
			(at 1.273556 2.498344 270)
			(size 1.4478 1.4478)
			(drill 1.0414)
			(layers "*.Cu" "*.Mask")
			(remove_unused_layers no)
			(net "GND")
			(clearance 0.1524)
			(thermal_gap 0.1524)
		)
		(pad "8" thru_hole circle
			(at -1.27 -0.4572 270)
			(size 0.7112 0.7112)
			(drill 0.4064)
			(layers "*.Cu" "*.Mask")
			(remove_unused_layers no)
			(net "GND")
			(clearance 0.1016)
			(thermal_gap 0.1016)
		)
		(pad "9" thru_hole circle
			(at -1.27 0.762 270)
			(size 0.7112 0.7112)
			(drill 0.4064)
			(layers "*.Cu" "*.Mask")
			(remove_unused_layers no)
			(net "GND")
			(clearance 0.1016)
			(thermal_gap 0.1016)
		)
		(pad "10" thru_hole circle
			(at 0.0254 0.762 270)
			(size 0.7112 0.7112)
			(drill 0.4064)
			(layers "*.Cu" "*.Mask")
			(remove_unused_layers no)
			(net "GND")
			(clearance 0.1016)
			(thermal_gap 0.1016)
		)
		(pad "11" thru_hole circle
			(at 1.27 0.762 270)
			(size 0.7112 0.7112)
			(drill 0.4064)
			(layers "*.Cu" "*.Mask")
			(remove_unused_layers no)
			(net "GND")
			(clearance 0.1016)
			(thermal_gap 0.1016)
		)
		(pad "12" thru_hole circle
			(at 1.27 -0.4572 270)
			(size 0.7112 0.7112)
			(drill 0.4064)
			(layers "*.Cu" "*.Mask")
			(remove_unused_layers no)
			(net "GND")
			(clearance 0.1016)
			(thermal_gap 0.1016)
		)
	)
)
